(kicad_pcb
	(version 20260206)
	(generator "pcbnew")
	(generator_version "10.0")
	(general
		(thickness 1.21888)
		(legacy_teardrops no)
	)
	(paper "A4")
	(title_block
		(title "timecard-beta-v1 — TimeCard-DC-V1.PcbDoc")
		(comment 1 "Time Appliance Project (Time Card) / footprints 80-95 of 120")
	)
	(layers
		(0 "F.Cu" signal "TOP")
		(4 "In1.Cu" signal "SGND")
		(6 "In2.Cu" signal "IN1")
		(8 "In3.Cu" signal "IN2")
		(10 "In4.Cu" signal "SGND1")
		(2 "B.Cu" signal "BOTTOM")
		(9 "F.Adhes" user "F.Adhesive")
		(11 "B.Adhes" user "B.Adhesive")
		(13 "F.Paste" user "Top Paste")
		(15 "B.Paste" user "Bottom Paste")
		(5 "F.SilkS" user "Top Overlay")
		(7 "B.SilkS" user "Bottom Overlay")
		(1 "F.Mask" user "Top Solder")
		(3 "B.Mask" user "Bottom Solder")
		(17 "Dwgs.User" user "User.Drawings")
		(19 "Cmts.User" user "User.Comments")
		(21 "Eco1.User" user "User.Eco1")
		(23 "Eco2.User" user "User.Eco2")
		(25 "Edge.Cuts" user)
		(27 "Margin" user)
		(31 "F.CrtYd" user "Top Courtyard")
		(29 "B.CrtYd" user "Bottom Courtyard")
		(35 "F.Fab" user "Top Component Center")
		(33 "B.Fab" user "Bottom Component Center")
	)
	(footprint "Vault:CAPC1608X87X45ML20T05"
		(layer "F.Cu")
		(at 227.648595 115.4666)
		(property "Reference" "C18"
			(at 1.74 0.905345 0)
			(unlocked yes)
			(layer "F.SilkS")
			(effects
				(font
					(size 0.762 0.762)
					(thickness 0.2286)
				)
				(justify left bottom)
			)
		)
		(property "Value" "0.1uF"
			(at 3.0099 9.82599 0)
			(unlocked yes)
			(layer "F.SilkS")
			(hide yes)
			(effects
				(font
					(size 1.524 1.524)
					(thickness 0.254)
				)
				(justify left bottom)
			)
		)
		(sheetname "POWER")
		(sheetfile "POWER.kicad_sch")
		(duplicate_pad_numbers_are_jumpers no)
		(pad "1" smd rect
			(at -0.7 0 90)
			(size 1.1 1.05)
			(layers "F.Cu" "F.Mask" "F.Paste")
			(net "GND")
		)
		(pad "2" smd rect
			(at 0.7 0 90)
			(size 1.1 1.05)
			(layers "F.Cu" "F.Mask" "F.Paste")
			(net "+5.0V")
		)
	)
	(footprint "Resistors:RESC2012X50N"
		(layer "F.Cu")
		(at 101.988595 65.3286 90)
		(property "Reference" "R19"
			(at -1.25 -5.156655 90)
			(unlocked yes)
			(layer "F.SilkS")
			(effects
				(font
					(size 0.762 0.762)
					(thickness 0.2286)
				)
				(justify left bottom)
			)
		)
		(property "Value" "CRCW080533R0FKEA"
			(at -3.52679 -1.5875 0)
			(unlocked yes)
			(layer "F.SilkS")
			(hide yes)
			(effects
				(font
					(size 1.524 1.524)
					(thickness 0.254)
				)
				(justify left bottom)
			)
		)
		(sheetname "PCIe_JTAG")
		(sheetfile "PCIe_JTAG.kicad_sch")
		(duplicate_pad_numbers_are_jumpers no)
		(fp_line
			(start 0 -0.762)
			(end 0 0.762)
			(stroke
				(width 0.1524)
				(type solid)
			)
			(layer "F.SilkS")
		)
		(pad "1" smd rect
			(at -1 0 180)
			(size 1.45 0.95)
			(layers "F.Cu" "F.Mask" "F.Paste")
			(net "FPGA_TDO")
		)
		(pad "2" smd rect
			(at 1 0 180)
			(size 1.45 0.95)
			(layers "F.Cu" "F.Mask" "F.Paste")
			(net "NetR19_2")
		)
	)
	(footprint "Vault:CAPC1608X87X45ML20T05"
		(layer "F.Cu")
		(at 214.059595 105.4336)
		(property "Reference" "C21"
			(at -4.371 0.538345 0)
			(unlocked yes)
			(layer "F.SilkS")
			(effects
				(font
					(size 0.762 0.762)
					(thickness 0.2286)
				)
				(justify left bottom)
			)
		)
		(property "Value" "0.1uF"
			(at 21.5011 -18.06321 0)
			(unlocked yes)
			(layer "F.SilkS")
			(hide yes)
			(effects
				(font
					(size 1.524 1.524)
					(thickness 0.254)
				)
				(justify left bottom)
			)
		)
		(sheetname "POWER")
		(sheetfile "POWER.kicad_sch")
		(duplicate_pad_numbers_are_jumpers no)
		(pad "1" smd rect
			(at -0.7 0 90)
			(size 1.1 1.05)
			(layers "F.Cu" "F.Mask" "F.Paste")
			(net "GND")
		)
		(pad "2" smd rect
			(at 0.7 0 90)
			(size 1.1 1.05)
			(layers "F.Cu" "F.Mask" "F.Paste")
			(net "NetC21_2")
		)
	)
	(footprint "Vault:RESC1608X55X25NL10T15"
		(layer "F.Cu")
		(at 83.238595 123.5786 -90)
		(property "Reference" "R15"
			(at 2.2714 -0.026931 90)
			(unlocked yes)
			(layer "F.SilkS")
			(effects
				(font
					(size 0.762 0.762)
					(thickness 0.2286)
				)
			)
		)
		(property "Value" "49.9R"
			(at 2.835402 -4.98946 0)
			(unlocked yes)
			(layer "F.SilkS")
			(hide yes)
			(effects
				(font
					(size 1.524 1.524)
					(thickness 0.254)
				)
			)
		)
		(sheetname "USER_IO")
		(sheetfile "USER_IO.kicad_sch")
		(duplicate_pad_numbers_are_jumpers no)
		(pad "1" smd rect
			(at -0.7 0)
			(size 0.9 0.7)
			(layers "F.Cu" "F.Mask" "F.Paste")
			(net "NetR15_1")
		)
		(pad "2" smd rect
			(at 0.7 0)
			(size 0.9 0.7)
			(layers "F.Cu" "F.Mask" "F.Paste")
			(net "NetAN3_1")
		)
	)
	(footprint "Capacitors:CAPC2012X14N"
		(layer "F.Cu")
		(at 133.488595 75.1786 -90)
		(property "Reference" "C58"
			(at 4.4 -0.843345 90)
			(unlocked yes)
			(layer "F.SilkS")
			(effects
				(font
					(size 0.762 0.762)
					(thickness 0.2286)
				)
				(justify left bottom)
			)
		)
		(property "Value" "CAP_0805_10UF_25V"
			(at 5.32679 1.5875 0)
			(unlocked yes)
			(layer "F.SilkS")
			(hide yes)
			(effects
				(font
					(size 1.524 1.524)
					(thickness 0.254)
				)
				(justify left bottom)
			)
		)
		(sheetname "GPS_IMU_SENSORS")
		(sheetfile "GPS_IMU_SENSORS.kicad_sch")
		(duplicate_pad_numbers_are_jumpers no)
		(fp_line
			(start 0.762 0.9652)
			(end -0.762 0.9652)
			(stroke
				(width 0.1524)
				(type solid)
			)
			(layer "F.SilkS")
		)
		(fp_line
			(start 0.762 -0.9652)
			(end -0.762 -0.9652)
			(stroke
				(width 0.1524)
				(type solid)
			)
			(layer "F.SilkS")
		)
		(pad "1" smd rect
			(at -0.9 0)
			(size 1.45 1.15)
			(layers "F.Cu" "F.Mask" "F.Paste")
			(net "+3.3V")
		)
		(pad "2" smd rect
			(at 0.9 0)
			(size 1.45 1.15)
			(layers "F.Cu" "F.Mask" "F.Paste")
			(net "GND")
		)
	)
	(footprint "Passives:SODFL370X135-2N"
		(layer "F.Cu")
		(at 105.688595 145.2786 -90)
		(property "Reference" "D3"
			(at -2.6 -0.393345 90)
			(unlocked yes)
			(layer "F.SilkS")
			(effects
				(font
					(size 0.762 0.762)
					(thickness 0.2286)
				)
				(justify left bottom)
			)
		)
		(property "Value" "DFLZ39-TP"
			(at 3.62839 2.0955 0)
			(unlocked yes)
			(layer "F.SilkS")
			(hide yes)
			(effects
				(font
					(size 1.524 1.524)
					(thickness 0.254)
				)
				(justify left bottom)
			)
		)
		(sheetname "POWER")
		(sheetfile "POWER.kicad_sch")
		(duplicate_pad_numbers_are_jumpers no)
		(fp_line
			(start -1.55 0.95)
			(end -1.55 0.825)
			(stroke
				(width 0.2)
				(type solid)
			)
			(layer "F.SilkS")
		)
		(fp_line
			(start 1.55 0.95)
			(end -1.55 0.95)
			(stroke
				(width 0.2)
				(type solid)
			)
			(layer "F.SilkS")
		)
		(fp_line
			(start 1.55 0.95)
			(end 1.55 0.825)
			(stroke
				(width 0.2)
				(type solid)
			)
			(layer "F.SilkS")
		)
		(fp_line
			(start -1.55 -0.825)
			(end -1.55 -0.95)
			(stroke
				(width 0.2)
				(type solid)
			)
			(layer "F.SilkS")
		)
		(fp_line
			(start 1.55 -0.825)
			(end 1.55 -0.95)
			(stroke
				(width 0.2)
				(type solid)
			)
			(layer "F.SilkS")
		)
		(fp_line
			(start 1.55 -0.95)
			(end -1.55 -0.95)
			(stroke
				(width 0.2)
				(type solid)
			)
			(layer "F.SilkS")
		)
		(fp_circle
			(center -2.05 -0.825)
			(end -2.1 -0.825)
			(stroke
				(width 0.1)
				(type solid)
			)
			(fill no)
			(layer "F.SilkS")
		)
		(pad "1" smd rect
			(at -1.825 0)
			(size 1.05 0.65)
			(layers "F.Cu" "F.Mask" "F.Paste")
			(net "NetD3_1")
		)
		(pad "2" smd rect
			(at 1.825 0)
			(size 1.05 0.65)
			(layers "F.Cu" "F.Mask" "F.Paste")
			(net "+12V_PCIE")
		)
	)
	(footprint "Vault:CAPC1608X87X45ML20T05"
		(layer "F.Cu")
		(at 227.648595 116.8636)
		(property "Reference" "C17"
			(at 1.74 0.708345 0)
			(unlocked yes)
			(layer "F.SilkS")
			(effects
				(font
					(size 0.762 0.762)
					(thickness 0.2286)
				)
				(justify left bottom)
			)
		)
		(property "Value" "0.1uF"
			(at 1.6129 8.42899 0)
			(unlocked yes)
			(layer "F.SilkS")
			(hide yes)
			(effects
				(font
					(size 1.524 1.524)
					(thickness 0.254)
				)
				(justify left bottom)
			)
		)
		(sheetname "POWER")
		(sheetfile "POWER.kicad_sch")
		(duplicate_pad_numbers_are_jumpers no)
		(pad "1" smd rect
			(at -0.7 0 90)
			(size 1.1 1.05)
			(layers "F.Cu" "F.Mask" "F.Paste")
			(net "GND")
		)
		(pad "2" smd rect
			(at 0.7 0 90)
			(size 1.1 1.05)
			(layers "F.Cu" "F.Mask" "F.Paste")
			(net "+5.0V")
		)
	)
	(footprint "Vault:RESC1608X55X30NL15T15"
		(layer "F.Cu")
		(at 118.738595 90.5786 90)
		(property "Reference" "R27"
			(at 3.2286 0.026931 90)
			(unlocked yes)
			(layer "F.SilkS")
			(effects
				(font
					(size 0.762 0.762)
					(thickness 0.2286)
				)
			)
		)
		(property "Value" "4.7K"
			(at -3.114802 2.39944 0)
			(unlocked yes)
			(layer "F.SilkS")
			(hide yes)
			(effects
				(font
					(size 1.524 1.524)
					(thickness 0.254)
				)
			)
		)
		(sheetname "GPS_IMU_SENSORS")
		(sheetfile "GPS_IMU_SENSORS.kicad_sch")
		(duplicate_pad_numbers_are_jumpers no)
		(pad "1" smd rect
			(at -0.75 0 180)
			(size 0.95 0.95)
			(layers "F.Cu" "F.Mask" "F.Paste")
			(net "SCL")
		)
		(pad "2" smd rect
			(at 0.75 0 180)
			(size 0.95 0.95)
			(layers "F.Cu" "F.Mask" "F.Paste")
			(net "+3.3V")
		)
	)
	(footprint "Vault:RESC1608X55X25NL10T15"
		(layer "F.Cu")
		(at 183.738595 89.0786 -90)
		(property "Reference" "R13"
			(at -2.7286 -0.026931 90)
			(unlocked yes)
			(layer "F.SilkS")
			(effects
				(font
					(size 0.762 0.762)
					(thickness 0.2286)
				)
			)
		)
		(property "Value" "49.9R"
			(at -2.911602 3.21199 180)
			(unlocked yes)
			(layer "F.SilkS")
			(hide yes)
			(effects
				(font
					(size 1.524 1.524)
					(thickness 0.254)
				)
			)
		)
		(sheetname "MAC")
		(sheetfile "MAC.kicad_sch")
		(duplicate_pad_numbers_are_jumpers no)
		(pad "1" smd rect
			(at -0.7 0)
			(size 0.9 0.7)
			(layers "F.Cu" "F.Mask" "F.Paste")
			(net "NetR13_1")
		)
		(pad "2" smd rect
			(at 0.7 0)
			(size 0.9 0.7)
			(layers "F.Cu" "F.Mask" "F.Paste")
			(net "FPGA_MAC_PPS_OUT-")
		)
	)
	(footprint "Resistors:RESC1608X50N"
		(layer "F.Cu")
		(at 210.988595 100.5786 -90)
		(property "Reference" "R9"
			(at -2.427 -0.395345 90)
			(unlocked yes)
			(layer "F.SilkS")
			(effects
				(font
					(size 0.762 0.762)
					(thickness 0.2286)
				)
				(justify left bottom)
			)
		)
		(property "Value" "ERJ-3EKF2201V"
			(at -8.25881 -27.9527 0)
			(unlocked yes)
			(layer "F.SilkS")
			(hide yes)
			(effects
				(font
					(size 1.524 1.524)
					(thickness 0.254)
				)
				(justify left bottom)
			)
		)
		(sheetname "POWER")
		(sheetfile "POWER.kicad_sch")
		(duplicate_pad_numbers_are_jumpers no)
		(fp_line
			(start 0 0.5)
			(end 0 -0.5)
			(stroke
				(width 0.1524)
				(type solid)
			)
			(layer "F.SilkS")
		)
		(pad "1" smd rect
			(at -0.69 0)
			(size 1 0.72)
			(layers "F.Cu" "F.Mask" "F.Paste")
			(net "GND")
		)
		(pad "2" smd rect
			(at 0.69 0)
			(size 1 0.72)
			(layers "F.Cu" "F.Mask" "F.Paste")
			(net "NetC22_1")
		)
	)
	(footprint "Resistors:RESC2012X50N"
		(layer "F.Cu")
		(at 109.738595 65.3286 90)
		(property "Reference" "R21"
			(at -1.25 -1.406655 90)
			(unlocked yes)
			(layer "F.SilkS")
			(effects
				(font
					(size 0.762 0.762)
					(thickness 0.2286)
				)
				(justify left bottom)
			)
		)
		(property "Value" "CRCW080533R0FKEA"
			(at -3.52679 -1.5875 0)
			(unlocked yes)
			(layer "F.SilkS")
			(hide yes)
			(effects
				(font
					(size 1.524 1.524)
					(thickness 0.254)
				)
				(justify left bottom)
			)
		)
		(sheetname "PCIe_JTAG")
		(sheetfile "PCIe_JTAG.kicad_sch")
		(duplicate_pad_numbers_are_jumpers no)
		(fp_line
			(start 0 -0.762)
			(end 0 0.762)
			(stroke
				(width 0.1524)
				(type solid)
			)
			(layer "F.SilkS")
		)
		(pad "1" smd rect
			(at -1 0 180)
			(size 1.45 0.95)
			(layers "F.Cu" "F.Mask" "F.Paste")
			(net "FPGA_TDI")
		)
		(pad "2" smd rect
			(at 1 0 180)
			(size 1.45 0.95)
			(layers "F.Cu" "F.Mask" "F.Paste")
			(net "NetR21_2")
		)
	)
	(footprint "GNSS:GNSS"
		(layer "F.Cu")
		(at 123.266095 71.5786)
		(property "Reference" "U9"
			(at -0.7775 -5.406655 360)
			(unlocked yes)
			(layer "F.SilkS")
			(effects
				(font
					(size 0.762 0.762)
					(thickness 0.2286)
				)
				(justify left bottom)
			)
		)
		(property "Value" "RCB-F9T"
			(at -9.8007 23.16699 0)
			(unlocked yes)
			(layer "F.SilkS")
			(hide yes)
			(effects
				(font
					(size 1.524 1.524)
					(thickness 0.254)
				)
				(justify left bottom)
			)
		)
		(sheetname "GPS_IMU_SENSORS")
		(sheetfile "GPS_IMU_SENSORS.kicad_sch")
		(duplicate_pad_numbers_are_jumpers no)
		(fp_line
			(start -6.11 -20.47)
			(end 61.07 -20.47)
			(stroke
				(width 0.254)
				(type solid)
			)
			(layer "F.SilkS")
		)
		(fp_line
			(start -6.11 11.28)
			(end -6.11 -20.47)
			(stroke
				(width 0.254)
				(type solid)
			)
			(layer "F.SilkS")
		)
		(fp_line
			(start -6.11 11.28)
			(end 61.07 11.28)
			(stroke
				(width 0.254)
				(type solid)
			)
			(layer "F.SilkS")
		)
		(fp_line
			(start 61.07 11.28)
			(end 61.07 -20.47)
			(stroke
				(width 0.254)
				(type solid)
			)
			(layer "F.SilkS")
		)
		(pad "0" thru_hole circle
			(at 0 -2 270)
			(size 0 0)
			(drill 0.76)
			(layers "*.Cu" "*.Mask")
			(remove_unused_layers no)
			(thermal_bridge_angle 90)
		)
		(pad "0" thru_hole circle
			(at 0 2 270)
			(size 0 0)
			(drill 0.76)
			(layers "*.Cu" "*.Mask")
			(remove_unused_layers no)
			(thermal_bridge_angle 90)
		)
		(pad "1" smd rect
			(at -2.2225 3 270)
			(size 1.12 2.105)
			(layers "F.Cu" "F.Mask" "F.Paste")
			(net "+5.0V")
		)
		(pad "2" smd rect
			(at 2.2225 3 270)
			(size 1.12 2.105)
			(layers "F.Cu" "F.Mask" "F.Paste")
			(net "+3.3V")
		)
		(pad "3" smd rect
			(at -2.2225 1 270)
			(size 1.12 2.105)
			(layers "F.Cu" "F.Mask" "F.Paste")
			(net "GPS1_TX")
		)
		(pad "4" smd rect
			(at 2.2225 1 270)
			(size 1.12 2.105)
			(layers "F.Cu" "F.Mask" "F.Paste")
			(net "GPS1_RST")
		)
		(pad "5" smd rect
			(at -2.2225 -1 270)
			(size 1.12 2.105)
			(layers "F.Cu" "F.Mask" "F.Paste")
			(net "GPS1_RX")
		)
		(pad "6" smd rect
			(at 2.2225 -1 270)
			(size 1.12 2.105)
			(layers "F.Cu" "F.Mask" "F.Paste")
			(net "GPS1_TP1")
		)
		(pad "7" smd rect
			(at -2.2225 -3 270)
			(size 1.12 2.105)
			(layers "F.Cu" "F.Mask" "F.Paste")
			(net "GPS1_TP2")
		)
		(pad "8" smd rect
			(at 2.2225 -3 270)
			(size 1.12 2.105)
			(layers "F.Cu" "F.Mask" "F.Paste")
			(net "GND")
		)
	)
	(footprint "Vault:TECO-1909763-1_V"
		(layer "F.Cu")
		(at 71.838595 110.9786 90)
		(property "Reference" "J5"
			(at -1.371395 2.926931 90)
			(unlocked yes)
			(layer "F.SilkS")
			(effects
				(font
					(size 0.762 0.762)
					(thickness 0.2286)
				)
			)
		)
		(property "Value" "1909763-1"
			(at 4.608085 3.749802 90)
			(unlocked yes)
			(layer "F.SilkS")
			(hide yes)
			(effects
				(font
					(size 1.524 1.524)
					(thickness 0.254)
				)
			)
		)
		(sheetname "USER_IO")
		(sheetfile "USER_IO.kicad_sch")
		(duplicate_pad_numbers_are_jumpers no)
		(fp_line
			(start -0.55 -1.3)
			(end 0.55 -1.3)
			(stroke
				(width 0.2)
				(type solid)
			)
			(layer "F.SilkS")
		)
		(fp_circle
			(center -1.778 1.65)
			(end -1.653 1.65)
			(stroke
				(width 0.25)
				(type solid)
			)
			(fill no)
			(layer "F.SilkS")
		)
		(pad "1" smd rect
			(at -1.475 0 90)
			(size 1.05 2.2)
			(layers "F.Cu" "F.Mask" "F.Paste")
			(net "GND")
		)
		(pad "2" smd rect
			(at 0 1.525 90)
			(size 1 1.05)
			(layers "F.Cu" "F.Mask" "F.Paste")
			(net "NetAN2_1")
		)
		(pad "3" smd rect
			(at 1.475 0 90)
			(size 1.05 2.2)
			(layers "F.Cu" "F.Mask" "F.Paste")
			(net "GND")
		)
	)
	(footprint "Vault:SOT143-4L"
		(layer "F.Cu")
		(at 72.488595 130.8286 90)
		(property "Reference" "D1"
			(at -2.776931 1.478605 360)
			(unlocked yes)
			(layer "F.SilkS")
			(effects
				(font
					(size 0.762 0.762)
					(thickness 0.2286)
				)
			)
		)
		(property "Value" "8240136"
			(at 2.7035 3.368802 90)
			(unlocked yes)
			(layer "F.SilkS")
			(hide yes)
			(effects
				(font
					(size 1.524 1.524)
					(thickness 0.254)
				)
			)
		)
		(sheetname "USER_IO")
		(sheetfile "USER_IO.kicad_sch")
		(duplicate_pad_numbers_are_jumpers no)
		(fp_line
			(start 2.05 -1.7)
			(end 2.05 1.7)
			(stroke
				(width 0.2)
				(type solid)
			)
			(layer "F.SilkS")
		)
		(fp_line
			(start -2.05 -1.7)
			(end 2.05 -1.7)
			(stroke
				(width 0.2)
				(type solid)
			)
			(layer "F.SilkS")
		)
		(fp_line
			(start -2.05 -1.7)
			(end -2.05 1.675)
			(stroke
				(width 0.2)
				(type solid)
			)
			(layer "F.SilkS")
		)
		(fp_line
			(start -2.05 1.7)
			(end 2.05 1.7)
			(stroke
				(width 0.2)
				(type solid)
			)
			(layer "F.SilkS")
		)
		(fp_circle
			(center -2.404 -1.075)
			(end -2.15 -1.075)
			(stroke
				(width 0.2)
				(type solid)
			)
			(fill no)
			(layer "F.SilkS")
		)
		(pad "1" smd rect
			(at -1.1 -0.75 180)
			(size 1.4 1.4)
			(layers "F.Cu" "F.Mask" "F.Paste")
			(net "GND")
		)
		(pad "2" smd rect
			(at -1.1 0.95 180)
			(size 1 1.4)
			(layers "F.Cu" "F.Mask" "F.Paste")
			(net "NetAN4_1")
		)
		(pad "3" smd rect
			(at 1.1 0.95 180)
			(size 1 1.4)
			(layers "F.Cu" "F.Mask" "F.Paste")
			(net "NetAN3_1")
		)
		(pad "4" smd rect
			(at 1.1 -0.95 180)
			(size 1 1.4)
			(layers "F.Cu" "F.Mask" "F.Paste")
			(net "+3.3V")
		)
	)
	(footprint "Vault:CAPC1608X87X45ML20T05"
		(layer "F.Cu")
		(at 233.109595 107.3386 180)
		(property "Reference" "C19"
			(at 1.046 1.141655 0)
			(unlocked yes)
			(layer "F.SilkS")
			(effects
				(font
					(size 0.762 0.762)
					(thickness 0.2286)
				)
				(justify left bottom)
			)
		)
		(property "Value" "0.1uF"
			(at 3.9751 -3.95859 0)
			(unlocked yes)
			(layer "F.SilkS")
			(hide yes)
			(effects
				(font
					(size 1.524 1.524)
					(thickness 0.254)
				)
				(justify left bottom)
			)
		)
		(sheetname "POWER")
		(sheetfile "POWER.kicad_sch")
		(duplicate_pad_numbers_are_jumpers no)
		(pad "1" smd rect
			(at -0.7 0 270)
			(size 1.1 1.05)
			(layers "F.Cu" "F.Mask" "F.Paste")
			(net "GND")
		)
		(pad "2" smd rect
			(at 0.7 0 270)
			(size 1.1 1.05)
			(layers "F.Cu" "F.Mask" "F.Paste")
			(net "NetC19_2")
		)
	)
	(footprint "Vault:CAPC1608X87X45ML20T05"
		(layer "F.Cu")
		(at 219.588595 90.9786 180)
		(property "Reference" "C9"
			(at 4.2 -0.493345 0)
			(unlocked yes)
			(layer "F.SilkS")
			(effects
				(font
					(size 0.762 0.762)
					(thickness 0.2286)
				)
				(justify left bottom)
			)
		)
		(property "Value" "0.1uF"
			(at -10.9347 -6.32079 0)
			(unlocked yes)
			(layer "F.SilkS")
			(hide yes)
			(effects
				(font
					(size 1.524 1.524)
					(thickness 0.254)
				)
				(justify left bottom)
			)
		)
		(sheetname "POWER")
		(sheetfile "POWER.kicad_sch")
		(duplicate_pad_numbers_are_jumpers no)
		(pad "1" smd rect
			(at -0.7 0 270)
			(size 1.1 1.05)
			(layers "F.Cu" "F.Mask" "F.Paste")
			(net "GND")
		)
		(pad "2" smd rect
			(at 0.7 0 270)
			(size 1.1 1.05)
			(layers "F.Cu" "F.Mask" "F.Paste")
			(net "+3.3V")
		)
	)
)
